(kicad_pcb
	(version 20260206)
	(generator "pcbnew")
	(generator_version "10.0")
	(general
		(thickness 1.6)
		(legacy_teardrops no)
	)
	(paper "A4")
	(title_block
		(title "netronome-mezz — pcbd0082-001_rev01_jul9_a.brd")
		(comment 1 "Open CloudServer (Microsoft) / footprints 88-94 of 714")
	)
	(layers
		(0 "F.Cu" signal "TOP")
		(4 "In1.Cu" signal "02_GND")
		(6 "In2.Cu" signal "03_SIG")
		(8 "In3.Cu" signal "04_SIG")
		(10 "In4.Cu" signal "05_GND")
		(12 "In5.Cu" signal "06_PWR1")
		(14 "In6.Cu" signal "07_SIG")
		(16 "In7.Cu" signal "08_SIG")
		(18 "In8.Cu" signal "09_GND")
		(2 "B.Cu" signal "BOTTOM")
		(9 "F.Adhes" user "F.Adhesive")
		(11 "B.Adhes" user "B.Adhesive")
		(13 "F.Paste" user "Package Geometry/Pastemask Top")
		(15 "B.Paste" user "Package Geometry/Pastemask Bottom")
		(5 "F.SilkS" user "Ref Des/Silkscreen Top")
		(7 "B.SilkS" user "Ref Des/Silkscreen Bottom")
		(1 "F.Mask" user "Board Geometry/Soldermask Top")
		(3 "B.Mask" user "Board Geometry/Soldermask Bottom")
		(17 "Dwgs.User" user "User.Drawings")
		(19 "Cmts.User" user "User.Comments")
		(21 "Eco1.User" user "User.Eco1")
		(23 "Eco2.User" user "User.Eco2")
		(25 "Edge.Cuts" user "Board Geometry/Outline")
		(27 "Margin" user)
		(31 "F.CrtYd" user "Package Geometry/Place Bound Top")
		(29 "B.CrtYd" user "Package Geometry/Place Bound Bottom")
		(35 "F.Fab" user "Ref Des/Assembly Top")
		(33 "B.Fab" user "Ref Des/Assembly Bottom")
		(45 "User.4" user "COMPVAL_TYPE_BOTTOM")
	)
	(footprint ""
		(layer "F.Cu")
		(at 34.925 43.0276)
		(property "Reference" "R327"
			(at 0.15367 3.556 90)
			(unlocked yes)
			(layer "F.SilkS")
			(effects
				(font
					(size 0.7874 0.5842)
					(thickness 0.127)
				)
				(justify left)
			)
		)
		(property "Value" "750"
			(at -0.148158 1.3462 90)
			(unlocked yes)
			(layer "F.Fab")
			(hide yes)
			(effects
				(font
					(size 1.27 0.9652)
					(thickness 0.000001)
				)
				(justify left)
			)
		)
		(property "Device Type" "REST0185"
			(at -0.148158 1.3462 90)
			(unlocked yes)
			(layer "F.Fab")
			(hide yes)
			(effects
				(font
					(size 1.27 0.9652)
					(thickness 0.000001)
				)
				(justify left)
			)
		)
		(duplicate_pad_numbers_are_jumpers no)
		(fp_poly
			(pts
				(xy 0.635 1.0668) (xy 0.635 -1.0668) (xy -0.635 -1.0668) (xy -0.635 1.0668)
			)
			(stroke
				(width 0)
				(type default)
			)
			(fill no)
			(layer "F.CrtYd")
		)
		(fp_line
			(start -0.254 -0.508)
			(end 0.254 -0.508)
			(stroke
				(width 0.0254)
				(type default)
			)
			(layer "F.Fab")
		)
		(fp_line
			(start -0.254 0.508)
			(end -0.254 -0.508)
			(stroke
				(width 0.0254)
				(type default)
			)
			(layer "F.Fab")
		)
		(fp_line
			(start 0.254 -0.508)
			(end 0.254 0.508)
			(stroke
				(width 0.0254)
				(type default)
			)
			(layer "F.Fab")
		)
		(fp_line
			(start 0.254 0.508)
			(end -0.254 0.508)
			(stroke
				(width 0.0254)
				(type default)
			)
			(layer "F.Fab")
		)
		(pad "1" smd rect
			(at 0 -0.4191)
			(size 0.508 0.5334)
			(layers "F.Cu" "F.Mask" "F.Paste")
			(net "10N2381")
		)
		(pad "2" smd rect
			(at 0 0.4191)
			(size 0.508 0.5334)
			(layers "F.Cu" "F.Mask" "F.Paste")
			(net "NFP_VDD_CORE_TCOMPA")
		)
		(zone
			(layer "F.Cu")
			(hatch none 0.5)
			(connect_pads
				(clearance 0)
			)
			(min_thickness 0.25)
			(keepout
				(tracks not_allowed)
				(vias allowed)
				(pads allowed)
				(copperpour not_allowed)
				(footprints allowed)
			)
			(placement
				(enabled no)
				(sheetname "")
			)
			(fill
				(thermal_gap 0.5)
				(thermal_bridge_width 0.5)
				(island_removal_mode 0)
			)
			(polygon
				(pts
					(xy 34.9504 43.0022) (xy 34.9504 43.053) (xy 34.8996 43.053) (xy 34.8996 43.0022)
				)
			)
		)
	)
	(footprint ""
		(layer "F.Cu")
		(at 80.137 26.924)
		(property "Reference" "R227"
			(at 0 0 0)
			(layer "F.SilkS")
			(hide yes)
			(effects
				(font
					(size 1.27 1.27)
				)
			)
		)
		(property "Value" "39.0"
			(at -0.148158 1.3462 90)
			(unlocked yes)
			(layer "F.Fab")
			(hide yes)
			(effects
				(font
					(size 1.27 0.9652)
					(thickness 0.000001)
				)
				(justify left)
			)
		)
		(property "Device Type" "REST0108"
			(at -0.148158 1.3462 90)
			(unlocked yes)
			(layer "F.Fab")
			(hide yes)
			(effects
				(font
					(size 1.27 0.9652)
					(thickness 0.000001)
				)
				(justify left)
			)
		)
		(duplicate_pad_numbers_are_jumpers no)
		(fp_poly
			(pts
				(xy 0.635 1.0668) (xy 0.635 -1.0668) (xy -0.635 -1.0668) (xy -0.635 1.0668)
			)
			(stroke
				(width 0)
				(type default)
			)
			(fill no)
			(layer "F.CrtYd")
		)
		(fp_line
			(start -0.254 -0.508)
			(end 0.254 -0.508)
			(stroke
				(width 0.0254)
				(type default)
			)
			(layer "F.Fab")
		)
		(fp_line
			(start -0.254 0.508)
			(end -0.254 -0.508)
			(stroke
				(width 0.0254)
				(type default)
			)
			(layer "F.Fab")
		)
		(fp_line
			(start 0.254 -0.508)
			(end 0.254 0.508)
			(stroke
				(width 0.0254)
				(type default)
			)
			(layer "F.Fab")
		)
		(fp_line
			(start 0.254 0.508)
			(end -0.254 0.508)
			(stroke
				(width 0.0254)
				(type default)
			)
			(layer "F.Fab")
		)
		(pad "1" smd rect
			(at 0 -0.4191)
			(size 0.508 0.5334)
			(layers "F.Cu" "F.Mask" "F.Paste")
			(net "DDR0_32A_WE_L")
		)
		(pad "2" smd rect
			(at 0 0.4191)
			(size 0.508 0.5334)
			(layers "F.Cu" "F.Mask" "F.Paste")
			(net "DDR_VTT")
		)
		(zone
			(layer "F.Cu")
			(hatch none 0.5)
			(connect_pads
				(clearance 0)
			)
			(min_thickness 0.25)
			(keepout
				(tracks not_allowed)
				(vias allowed)
				(pads allowed)
				(copperpour not_allowed)
				(footprints allowed)
			)
			(placement
				(enabled no)
				(sheetname "")
			)
			(fill
				(thermal_gap 0.5)
				(thermal_bridge_width 0.5)
				(island_removal_mode 0)
			)
			(polygon
				(pts
					(xy 80.1624 26.8986) (xy 80.1624 26.9494) (xy 80.1116 26.9494) (xy 80.1116 26.8986)
				)
			)
		)
	)
	(footprint ""
		(layer "F.Cu")
		(at 53.086 54.5338 -90)
		(property "Reference" "C65"
			(at 1.49987 1.016 0)
			(unlocked yes)
			(layer "F.SilkS")
			(effects
				(font
					(size 0.7874 0.5842)
					(thickness 0.127)
				)
				(justify left)
			)
		)
		(property "Value" "100UF"
			(at -0.78232 0.4826 0)
			(unlocked yes)
			(layer "F.Fab")
			(hide yes)
			(effects
				(font
					(size 1.27 0.9652)
					(thickness 0.000001)
				)
				(justify left)
			)
		)
		(property "Device Type" "CAPC0087"
			(at -0.78232 0.4826 0)
			(unlocked yes)
			(layer "F.Fab")
			(hide yes)
			(effects
				(font
					(size 1.27 0.9652)
					(thickness 0.000001)
				)
				(justify left)
			)
		)
		(duplicate_pad_numbers_are_jumpers no)
		(fp_circle
			(center 0 0)
			(end 0 -0.508)
			(stroke
				(width 0.2032)
				(type default)
			)
			(fill no)
			(layer "F.SilkS")
		)
		(fp_circle
			(center 0 0)
			(end 0 -0.508)
			(stroke
				(width 0.2032)
				(type default)
			)
			(fill no)
			(layer "F.SilkS")
		)
		(fp_poly
			(pts
				(xy -1.27 2.9464) (xy 1.021664 2.9464) (xy 1.021664 -2.9464) (xy -1.27 -2.9464)
			)
			(stroke
				(width 0)
				(type default)
			)
			(fill no)
			(layer "F.CrtYd")
		)
		(fp_line
			(start -1.016 2.794)
			(end -1.016 -2.794)
			(stroke
				(width 0.0254)
				(type default)
			)
			(layer "F.Fab")
		)
		(fp_line
			(start 1.016 2.794)
			(end -1.016 2.794)
			(stroke
				(width 0.0254)
				(type default)
			)
			(layer "F.Fab")
		)
		(fp_line
			(start -1.016 -2.794)
			(end 1.016 -2.794)
			(stroke
				(width 0.0254)
				(type default)
			)
			(layer "F.Fab")
		)
		(fp_line
			(start 1.016 -2.794)
			(end 1.016 2.794)
			(stroke
				(width 0.0254)
				(type default)
			)
			(layer "F.Fab")
		)
		(pad "1" smd rect
			(at 0 -1.6764 270)
			(size 1.524 1.524)
			(layers "F.Cu" "F.Mask" "F.Paste")
			(net "VDD_CORE")
		)
		(pad "2" smd rect
			(at 0 1.6764 270)
			(size 1.524 1.524)
			(layers "F.Cu" "F.Mask" "F.Paste")
			(net "GND")
		)
		(zone
			(layer "F.Cu")
			(hatch none 0.5)
			(connect_pads
				(clearance 0)
			)
			(min_thickness 0.25)
			(keepout
				(tracks allowed)
				(vias not_allowed)
				(pads allowed)
				(copperpour not_allowed)
				(footprints allowed)
			)
			(placement
				(enabled no)
				(sheetname "")
			)
			(fill
				(thermal_gap 0.5)
				(thermal_bridge_width 0.5)
				(island_removal_mode 0)
			)
			(polygon
				(pts
					(xy 51.4858 53.7464) (xy 51.4858 55.3212) (xy 54.6862 55.3212) (xy 54.6862 53.7464)
				)
			)
		)
		(zone
			(layer "F.Cu")
			(hatch none 0.5)
			(connect_pads
				(clearance 0)
			)
			(min_thickness 0.25)
			(keepout
				(tracks not_allowed)
				(vias allowed)
				(pads allowed)
				(copperpour not_allowed)
				(footprints allowed)
			)
			(placement
				(enabled no)
				(sheetname "")
			)
			(fill
				(thermal_gap 0.5)
				(thermal_bridge_width 0.5)
				(island_removal_mode 0)
			)
			(polygon
				(pts
					(xy 52.3494 53.7464) (xy 52.3494 55.3212) (xy 52.197 55.3212) (xy 52.197 53.7464)
				)
			)
		)
		(zone
			(layer "F.Cu")
			(hatch none 0.5)
			(connect_pads
				(clearance 0)
			)
			(min_thickness 0.25)
			(keepout
				(tracks not_allowed)
				(vias allowed)
				(pads allowed)
				(copperpour not_allowed)
				(footprints allowed)
			)
			(placement
				(enabled no)
				(sheetname "")
			)
			(fill
				(thermal_gap 0.5)
				(thermal_bridge_width 0.5)
				(island_removal_mode 0)
			)
			(polygon
				(pts
					(xy 53.975 53.7464) (xy 53.975 55.3212) (xy 53.8226 55.3212) (xy 53.8226 53.7464)
				)
			)
		)
	)
	(footprint ""
		(layer "F.Cu")
		(at 36.068 34.9758 90)
		(property "Reference" "C124"
			(at 0.86233 -1.27 0)
			(unlocked yes)
			(layer "F.SilkS")
			(effects
				(font
					(size 0.7874 0.5842)
					(thickness 0.127)
				)
				(justify left)
			)
		)
		(property "Value" "0.1UF"
			(at -0.091846 0.2921 180)
			(unlocked yes)
			(layer "F.Fab")
			(hide yes)
			(effects
				(font
					(size 0.7874 0.5842)
					(thickness 0.2032)
				)
				(justify left)
			)
		)
		(property "Device Type" "CAPC0073"
			(at -0.091846 0.2921 180)
			(unlocked yes)
			(layer "F.Fab")
			(hide yes)
			(effects
				(font
					(size 0.7874 0.5842)
					(thickness 0.2032)
				)
				(justify left)
			)
		)
		(duplicate_pad_numbers_are_jumpers no)
		(fp_poly
			(pts
				(xy 0.635 1.0668) (xy 0.635 -1.0668) (xy -0.635 -1.0668) (xy -0.635 1.0668)
			)
			(stroke
				(width 0)
				(type default)
			)
			(fill no)
			(layer "F.CrtYd")
		)
		(fp_line
			(start 0.254 -0.508)
			(end 0.254 0.508)
			(stroke
				(width 0.0254)
				(type default)
			)
			(layer "F.Fab")
		)
		(fp_line
			(start -0.254 -0.508)
			(end 0.254 -0.508)
			(stroke
				(width 0.0254)
				(type default)
			)
			(layer "F.Fab")
		)
		(fp_line
			(start 0.254 0.508)
			(end -0.254 0.508)
			(stroke
				(width 0.0254)
				(type default)
			)
			(layer "F.Fab")
		)
		(fp_line
			(start -0.254 0.508)
			(end -0.254 -0.508)
			(stroke
				(width 0.0254)
				(type default)
			)
			(layer "F.Fab")
		)
		(pad "1" smd rect
			(at 0 -0.4191 90)
			(size 0.508 0.5334)
			(layers "F.Cu" "F.Mask" "F.Paste")
			(net "10N2370")
		)
		(pad "2" smd rect
			(at 0 0.4191 90)
			(size 0.508 0.5334)
			(layers "F.Cu" "F.Mask" "F.Paste")
			(net "GND")
		)
		(zone
			(layer "F.Cu")
			(hatch none 0.5)
			(connect_pads
				(clearance 0)
			)
			(min_thickness 0.25)
			(keepout
				(tracks not_allowed)
				(vias allowed)
				(pads allowed)
				(copperpour not_allowed)
				(footprints allowed)
			)
			(placement
				(enabled no)
				(sheetname "")
			)
			(fill
				(thermal_gap 0.5)
				(thermal_bridge_width 0.5)
				(island_removal_mode 0)
			)
			(polygon
				(pts
					(xy 36.0426 34.9504) (xy 36.0934 34.9504) (xy 36.0934 35.0012) (xy 36.0426 35.0012)
				)
			)
		)
	)
	(footprint ""
		(layer "F.Cu")
		(at 33.6042 43.434 90)
		(property "Reference" "C34"
			(at 0 0 90)
			(layer "F.SilkS")
			(hide yes)
			(effects
				(font
					(size 1.27 1.27)
				)
			)
		)
		(property "Value" "6800PF"
			(at -0.091846 0.2921 180)
			(unlocked yes)
			(layer "F.Fab")
			(hide yes)
			(effects
				(font
					(size 0.7874 0.5842)
					(thickness 0.2032)
				)
				(justify left)
			)
		)
		(property "Device Type" "CAPC0079"
			(at -0.091846 0.2921 180)
			(unlocked yes)
			(layer "F.Fab")
			(hide yes)
			(effects
				(font
					(size 0.7874 0.5842)
					(thickness 0.2032)
				)
				(justify left)
			)
		)
		(duplicate_pad_numbers_are_jumpers no)
		(fp_poly
			(pts
				(xy 0.635 1.0668) (xy 0.635 -1.0668) (xy -0.635 -1.0668) (xy -0.635 1.0668)
			)
			(stroke
				(width 0)
				(type default)
			)
			(fill no)
			(layer "F.CrtYd")
		)
		(fp_line
			(start 0.254 -0.508)
			(end 0.254 0.508)
			(stroke
				(width 0.0254)
				(type default)
			)
			(layer "F.Fab")
		)
		(fp_line
			(start -0.254 -0.508)
			(end 0.254 -0.508)
			(stroke
				(width 0.0254)
				(type default)
			)
			(layer "F.Fab")
		)
		(fp_line
			(start 0.254 0.508)
			(end -0.254 0.508)
			(stroke
				(width 0.0254)
				(type default)
			)
			(layer "F.Fab")
		)
		(fp_line
			(start -0.254 0.508)
			(end -0.254 -0.508)
			(stroke
				(width 0.0254)
				(type default)
			)
			(layer "F.Fab")
		)
		(pad "1" smd rect
			(at 0 -0.4191 90)
			(size 0.508 0.5334)
			(layers "F.Cu" "F.Mask" "F.Paste")
			(net "10N2528")
		)
		(pad "2" smd rect
			(at 0 0.4191 90)
			(size 0.508 0.5334)
			(layers "F.Cu" "F.Mask" "F.Paste")
			(net "NFP_VDD_CORE_TCOMPA")
		)
		(zone
			(layer "F.Cu")
			(hatch none 0.5)
			(connect_pads
				(clearance 0)
			)
			(min_thickness 0.25)
			(keepout
				(tracks not_allowed)
				(vias allowed)
				(pads allowed)
				(copperpour not_allowed)
				(footprints allowed)
			)
			(placement
				(enabled no)
				(sheetname "")
			)
			(fill
				(thermal_gap 0.5)
				(thermal_bridge_width 0.5)
				(island_removal_mode 0)
			)
			(polygon
				(pts
					(xy 33.5788 43.4086) (xy 33.6296 43.4086) (xy 33.6296 43.4594) (xy 33.5788 43.4594)
				)
			)
		)
	)
	(footprint ""
		(layer "F.Cu")
		(at 18.3515 34.3281 180)
		(property "Reference" "C23"
			(at -0.02667 -3.556 90)
			(unlocked yes)
			(layer "F.SilkS")
			(effects
				(font
					(size 0.7874 0.5842)
					(thickness 0.127)
				)
				(justify left)
			)
		)
		(property "Value" "22UF"
			(at -0.148158 1.7526 270)
			(unlocked yes)
			(layer "F.Fab")
			(hide yes)
			(effects
				(font
					(size 1.27 0.9652)
					(thickness 0.000001)
				)
				(justify left)
			)
		)
		(property "Device Type" "CAPC0063"
			(at -0.148158 1.7526 270)
			(unlocked yes)
			(layer "F.Fab")
			(hide yes)
			(effects
				(font
					(size 1.27 0.9652)
					(thickness 0.000001)
				)
				(justify left)
			)
		)
		(duplicate_pad_numbers_are_jumpers no)
		(fp_circle
			(center 0 0)
			(end -0.127 0)
			(stroke
				(width 0.2032)
				(type default)
			)
			(fill no)
			(layer "F.SilkS")
		)
		(fp_poly
			(pts
				(xy 0.7874 -1.6637) (xy -0.7874 -1.6637) (xy -0.7874 1.6637) (xy 0.7874 1.6637)
			)
			(stroke
				(width 0)
				(type default)
			)
			(fill no)
			(layer "F.CrtYd")
		)
		(fp_line
			(start 0.4064 0.8128)
			(end -0.4064 0.8128)
			(stroke
				(width 0.0254)
				(type default)
			)
			(layer "F.Fab")
		)
		(fp_line
			(start 0.4064 -0.7874)
			(end 0.4064 0.8128)
			(stroke
				(width 0.0254)
				(type default)
			)
			(layer "F.Fab")
		)
		(fp_line
			(start -0.4064 0.8128)
			(end -0.4064 -0.7874)
			(stroke
				(width 0.0254)
				(type default)
			)
			(layer "F.Fab")
		)
		(fp_line
			(start -0.4064 -0.7874)
			(end 0.4064 -0.7874)
			(stroke
				(width 0.0254)
				(type default)
			)
			(layer "F.Fab")
		)
		(pad "1" smd rect
			(at 0 -0.8001 180)
			(size 0.8636 0.9652)
			(layers "F.Cu" "F.Mask" "F.Paste")
			(net "VDD_3.3V")
		)
		(pad "2" smd rect
			(at 0 0.8001 180)
			(size 0.8636 0.9652)
			(layers "F.Cu" "F.Mask" "F.Paste")
			(net "GND")
		)
		(zone
			(layer "F.Cu")
			(hatch none 0.5)
			(connect_pads
				(clearance 0)
			)
			(min_thickness 0.25)
			(keepout
				(tracks not_allowed)
				(vias allowed)
				(pads allowed)
				(copperpour not_allowed)
				(footprints allowed)
			)
			(placement
				(enabled no)
				(sheetname "")
			)
			(fill
				(thermal_gap 0.5)
				(thermal_bridge_width 0.5)
				(island_removal_mode 0)
			)
			(polygon
				(pts
					(xy 18.415 34.5821) (xy 18.288 34.5821) (xy 18.288 34.0741) (xy 18.415 34.0741)
				)
			)
		)
	)
	(footprint ""
		(layer "F.Cu")
		(at 17.907 26.67)
		(property "Reference" "R34"
			(at 0.66167 -0.635 90)
			(unlocked yes)
			(layer "F.SilkS")
			(effects
				(font
					(size 0.7874 0.5842)
					(thickness 0.127)
				)
				(justify left)
			)
		)
		(property "Value" "4.75K"
			(at -0.148158 1.3462 90)
			(unlocked yes)
			(layer "F.Fab")
			(hide yes)
			(effects
				(font
					(size 1.27 0.9652)
					(thickness 0.000001)
				)
				(justify left)
			)
		)
		(property "Device Type" "REST4024"
			(at -0.148158 1.3462 90)
			(unlocked yes)
			(layer "F.Fab")
			(hide yes)
			(effects
				(font
					(size 1.27 0.9652)
					(thickness 0.000001)
				)
				(justify left)
			)
		)
		(duplicate_pad_numbers_are_jumpers no)
		(fp_poly
			(pts
				(xy 0.635 1.0668) (xy 0.635 -1.0668) (xy -0.635 -1.0668) (xy -0.635 1.0668)
			)
			(stroke
				(width 0)
				(type default)
			)
			(fill no)
			(layer "F.CrtYd")
		)
		(fp_line
			(start -0.254 -0.508)
			(end 0.254 -0.508)
			(stroke
				(width 0.0254)
				(type default)
			)
			(layer "F.Fab")
		)
		(fp_line
			(start -0.254 0.508)
			(end -0.254 -0.508)
			(stroke
				(width 0.0254)
				(type default)
			)
			(layer "F.Fab")
		)
		(fp_line
			(start 0.254 -0.508)
			(end 0.254 0.508)
			(stroke
				(width 0.0254)
				(type default)
			)
			(layer "F.Fab")
		)
		(fp_line
			(start 0.254 0.508)
			(end -0.254 0.508)
			(stroke
				(width 0.0254)
				(type default)
			)
			(layer "F.Fab")
		)
		(pad "1" smd rect
			(at 0 -0.4191)
			(size 0.508 0.5334)
			(layers "F.Cu" "F.Mask" "F.Paste")
			(net "NFP_FAIL_SAFE_BOOT_L")
		)
		(pad "2" smd rect
			(at 0 0.4191)
			(size 0.508 0.5334)
			(layers "F.Cu" "F.Mask" "F.Paste")
			(net "VDD_3.3V")
		)
		(zone
			(layer "F.Cu")
			(hatch none 0.5)
			(connect_pads
				(clearance 0)
			)
			(min_thickness 0.25)
			(keepout
				(tracks not_allowed)
				(vias allowed)
				(pads allowed)
				(copperpour not_allowed)
				(footprints allowed)
			)
			(placement
				(enabled no)
				(sheetname "")
			)
			(fill
				(thermal_gap 0.5)
				(thermal_bridge_width 0.5)
				(island_removal_mode 0)
			)
			(polygon
				(pts
					(xy 17.9324 26.6446) (xy 17.9324 26.6954) (xy 17.8816 26.6954) (xy 17.8816 26.6446)
				)
			)
		)
	)
)
